(kicad_pcb
	(version 20260206)
	(generator "pcbnew")
	(generator_version "10.0")
	(general
		(thickness 1.6)
		(legacy_teardrops no)
	)
	(paper "A4")
	(title_block
		(title "pdpb — Lightning_PDPB_BRD.brd")
		(comment 1 "Lightning (Wiwynn / Facebook NVMe JBOF) / footprints 650-655 of 1140")
	)
	(layers
		(0 "F.Cu" signal "TOP")
		(4 "In1.Cu" signal "L2GND")
		(6 "In2.Cu" signal "L3")
		(8 "In3.Cu" signal "L4VCC")
		(10 "In4.Cu" signal "L5VCC")
		(12 "In5.Cu" signal "L6")
		(14 "In6.Cu" signal "L7GND")
		(2 "B.Cu" signal "BOTTOM")
		(9 "F.Adhes" user "F.Adhesive")
		(11 "B.Adhes" user "B.Adhesive")
		(13 "F.Paste" user "Package Geometry/Pastemask Top")
		(15 "B.Paste" user "Package Geometry/Pastemask Bottom")
		(5 "F.SilkS" user "Ref Des/Silkscreen Top")
		(7 "B.SilkS" user "Ref Des/Silkscreen Bottom")
		(1 "F.Mask" user "Board Geometry/Soldermask Top")
		(3 "B.Mask" user "Board Geometry/Soldermask Bottom")
		(17 "Dwgs.User" user "User.Drawings")
		(19 "Cmts.User" user "User.Comments")
		(21 "Eco1.User" user "User.Eco1")
		(23 "Eco2.User" user "User.Eco2")
		(25 "Edge.Cuts" user "Board Geometry/Outline")
		(27 "Margin" user)
		(31 "F.CrtYd" user "Package Geometry/Place Bound Top")
		(29 "B.CrtYd" user "Package Geometry/Place Bound Bottom")
		(35 "F.Fab" user "Ref Des/Assembly Top")
		(33 "B.Fab" user "Ref Des/Assembly Bottom")
	)
	(footprint ""
		(layer "F.Cu")
		(at 234.061 -452.628 -90)
		(property "Reference" "R120"
			(at 0 0 270)
			(layer "F.SilkS")
			(hide yes)
			(effects
				(font
					(size 1.27 1.27)
				)
			)
		)
		(property "Value" "100R2J-2-GP"
			(at 0.064008 -3.993896 270)
			(unlocked yes)
			(layer "F.Fab")
			(hide yes)
			(effects
				(font
					(size 1.016 1.016)
					(thickness 0.1524)
				)
			)
		)
		(property "Device Type" "R402H14"
			(at 0.064008 -5.517896 270)
			(unlocked yes)
			(layer "F.Fab")
			(hide yes)
			(effects
				(font
					(size 1.016 1.016)
					(thickness 0.1524)
				)
			)
		)
		(duplicate_pad_numbers_are_jumpers no)
		(fp_line
			(start -0.508 -0.9398)
			(end -0.508 0.9398)
			(stroke
				(width 0.1524)
				(type default)
			)
			(layer "F.SilkS")
		)
		(fp_line
			(start 0.508 -0.9398)
			(end -0.508 -0.9398)
			(stroke
				(width 0.1524)
				(type default)
			)
			(layer "F.SilkS")
		)
		(fp_rect
			(start -0.508 0.9398)
			(end 0.508 -0.9398)
			(stroke
				(width 0)
				(type default)
			)
			(fill no)
			(layer "F.CrtYd")
		)
		(fp_rect
			(start -0.508 0.9398)
			(end 0.508 -0.9398)
			(stroke
				(width 0)
				(type default)
			)
			(fill no)
			(layer "F.Fab")
		)
		(pad "1" smd custom
			(at 0 -0.4445 270)
			(size 0.1397 0.1397)
			(layers "F.Cu" "F.Mask" "F.Paste")
			(net "P3V3")
			(options
				(clearance outline)
				(anchor circle)
			)
			(primitives
				(gr_poly
					(pts
						(arc
							(start -0.1778 -0.2794)
							(mid -0.249642 -0.249642)
							(end -0.2794 -0.1778)
						)
						(arc
							(start -0.2794 0.1778)
							(mid -0.249642 0.249642)
							(end -0.1778 0.2794)
						)
						(arc
							(start 0.1778 0.2794)
							(mid 0.249642 0.249642)
							(end 0.2794 0.1778)
						)
						(arc
							(start 0.2794 -0.1778)
							(mid 0.249642 -0.249642)
							(end 0.1778 -0.2794)
						)
					)
					(width 0)
					(fill yes)
				)
			)
		)
		(pad "2" smd custom
			(at 0 0.4445 270)
			(size 0.1397 0.1397)
			(layers "F.Cu" "F.Mask" "F.Paste")
			(net "DRV_ACT_0")
			(options
				(clearance outline)
				(anchor circle)
			)
			(primitives
				(gr_poly
					(pts
						(arc
							(start -0.1778 -0.2794)
							(mid -0.249642 -0.249642)
							(end -0.2794 -0.1778)
						)
						(arc
							(start -0.2794 0.1778)
							(mid -0.249642 0.249642)
							(end -0.1778 0.2794)
						)
						(arc
							(start 0.1778 0.2794)
							(mid 0.249642 0.249642)
							(end 0.2794 0.1778)
						)
						(arc
							(start 0.2794 -0.1778)
							(mid 0.249642 -0.249642)
							(end 0.1778 -0.2794)
						)
					)
					(width 0)
					(fill yes)
				)
			)
		)
	)
	(footprint ""
		(layer "F.Cu")
		(at 11.43 -269.875 180)
		(property "Reference" "R9035"
			(at 0 0 180)
			(layer "F.SilkS")
			(hide yes)
			(effects
				(font
					(size 1.27 1.27)
				)
			)
		)
		(property "Value" "0R2J-2-GP"
			(at 0.064008 -3.993896 180)
			(unlocked yes)
			(layer "F.Fab")
			(hide yes)
			(effects
				(font
					(size 1.016 1.016)
					(thickness 0.1524)
				)
			)
		)
		(property "Device Type" "R402H16"
			(at 0.064008 -5.517896 180)
			(unlocked yes)
			(layer "F.Fab")
			(hide yes)
			(effects
				(font
					(size 1.016 1.016)
					(thickness 0.1524)
				)
			)
		)
		(duplicate_pad_numbers_are_jumpers no)
		(fp_line
			(start 0.508 -0.9398)
			(end -0.508 -0.9398)
			(stroke
				(width 0.1524)
				(type default)
			)
			(layer "F.SilkS")
		)
		(fp_line
			(start -0.508 -0.9398)
			(end -0.508 0.9398)
			(stroke
				(width 0.1524)
				(type default)
			)
			(layer "F.SilkS")
		)
		(fp_rect
			(start -0.508 0.9398)
			(end 0.508 -0.9398)
			(stroke
				(width 0)
				(type default)
			)
			(fill no)
			(layer "F.CrtYd")
		)
		(fp_rect
			(start -0.508 0.9398)
			(end 0.508 -0.9398)
			(stroke
				(width 0)
				(type default)
			)
			(fill no)
			(layer "F.Fab")
		)
		(pad "1" smd custom
			(at 0 -0.4445 180)
			(size 0.1397 0.1397)
			(layers "F.Cu" "F.Mask" "F.Paste")
			(net "TRAY_ID_R")
			(options
				(clearance outline)
				(anchor circle)
			)
			(primitives
				(gr_poly
					(pts
						(arc
							(start -0.1778 -0.2794)
							(mid -0.249642 -0.249642)
							(end -0.2794 -0.1778)
						)
						(arc
							(start -0.2794 0.1778)
							(mid -0.249642 0.249642)
							(end -0.1778 0.2794)
						)
						(arc
							(start 0.1778 0.2794)
							(mid 0.249642 0.249642)
							(end 0.2794 0.1778)
						)
						(arc
							(start 0.2794 -0.1778)
							(mid 0.249642 -0.249642)
							(end 0.1778 -0.2794)
						)
					)
					(width 0)
					(fill yes)
				)
			)
		)
		(pad "2" smd custom
			(at 0 0.4445 180)
			(size 0.1397 0.1397)
			(layers "F.Cu" "F.Mask" "F.Paste")
			(net "TRAY_ID")
			(options
				(clearance outline)
				(anchor circle)
			)
			(primitives
				(gr_poly
					(pts
						(arc
							(start -0.1778 -0.2794)
							(mid -0.249642 -0.249642)
							(end -0.2794 -0.1778)
						)
						(arc
							(start -0.2794 0.1778)
							(mid -0.249642 0.249642)
							(end -0.1778 0.2794)
						)
						(arc
							(start 0.1778 0.2794)
							(mid 0.249642 0.249642)
							(end 0.2794 0.1778)
						)
						(arc
							(start 0.2794 -0.1778)
							(mid 0.249642 -0.249642)
							(end 0.1778 -0.2794)
						)
					)
					(width 0)
					(fill yes)
				)
			)
		)
	)
	(footprint ""
		(layer "F.Cu")
		(at 94.488 -218.44 180)
		(property "Reference" "C8861"
			(at 0 0 180)
			(layer "F.SilkS")
			(hide yes)
			(effects
				(font
					(size 1.27 1.27)
				)
			)
		)
		(property "Value" "SCD1U16V2KX-3GP"
			(at 1.1811 -2.7051 180)
			(unlocked yes)
			(layer "F.Fab")
			(hide yes)
			(effects
				(font
					(size 1.016 1.016)
					(thickness 0.1524)
				)
			)
		)
		(property "Device Type" "C402H22"
			(at 1.1811 -4.2291 180)
			(unlocked yes)
			(layer "F.Fab")
			(hide yes)
			(effects
				(font
					(size 1.016 1.016)
					(thickness 0.1524)
				)
			)
		)
		(duplicate_pad_numbers_are_jumpers no)
		(fp_rect
			(start -0.4318 0.9525)
			(end 0.4318 -0.9525)
			(stroke
				(width 0)
				(type default)
			)
			(fill no)
			(layer "F.CrtYd")
		)
		(fp_rect
			(start -0.4318 0.9525)
			(end 0.4318 -0.9525)
			(stroke
				(width 0)
				(type default)
			)
			(fill no)
			(layer "F.Fab")
		)
		(pad "1" smd custom
			(at 0 -0.4445 180)
			(size 0.1524 0.1524)
			(layers "F.Cu" "F.Mask" "F.Paste")
			(net "VDD_IO_3")
			(options
				(clearance outline)
				(anchor circle)
			)
			(primitives
				(gr_poly
					(pts
						(arc
							(start 0.3048 -0.2032)
							(mid 0.275042 -0.275042)
							(end 0.2032 -0.3048)
						)
						(arc
							(start -0.2032 -0.3048)
							(mid -0.275042 -0.275042)
							(end -0.3048 -0.2032)
						)
						(arc
							(start -0.3048 0.2032)
							(mid -0.275042 0.275042)
							(end -0.2032 0.3048)
						)
						(arc
							(start 0.2032 0.3048)
							(mid 0.275042 0.275042)
							(end 0.3048 0.2032)
						)
					)
					(width 0)
					(fill yes)
				)
			)
		)
		(pad "2" smd custom
			(at 0 0.4445 180)
			(size 0.1524 0.1524)
			(layers "F.Cu" "F.Mask" "F.Paste")
			(net "GND")
			(options
				(clearance outline)
				(anchor circle)
			)
			(primitives
				(gr_poly
					(pts
						(arc
							(start 0.3048 -0.2032)
							(mid 0.275042 -0.275042)
							(end 0.2032 -0.3048)
						)
						(arc
							(start -0.2032 -0.3048)
							(mid -0.275042 -0.275042)
							(end -0.3048 -0.2032)
						)
						(arc
							(start -0.3048 0.2032)
							(mid -0.275042 0.275042)
							(end -0.2032 0.3048)
						)
						(arc
							(start 0.2032 0.3048)
							(mid 0.275042 0.275042)
							(end 0.3048 0.2032)
						)
					)
					(width 0)
					(fill yes)
				)
			)
		)
	)
	(footprint ""
		(layer "F.Cu")
		(at 234.061 -33.008062 90)
		(property "Reference" "R9807"
			(at 0 0 90)
			(layer "F.SilkS")
			(hide yes)
			(effects
				(font
					(size 1.27 1.27)
				)
			)
		)
		(property "Value" "0R2J-2-GP"
			(at 0.064008 -3.993896 90)
			(unlocked yes)
			(layer "F.Fab")
			(hide yes)
			(effects
				(font
					(size 1.016 1.016)
					(thickness 0.1524)
				)
			)
		)
		(property "Device Type" "R402H16"
			(at 0.064008 -5.517896 90)
			(unlocked yes)
			(layer "F.Fab")
			(hide yes)
			(effects
				(font
					(size 1.016 1.016)
					(thickness 0.1524)
				)
			)
		)
		(duplicate_pad_numbers_are_jumpers no)
		(fp_line
			(start 0.508 -0.9398)
			(end -0.508 -0.9398)
			(stroke
				(width 0.1524)
				(type default)
			)
			(layer "F.SilkS")
		)
		(fp_line
			(start -0.508 -0.9398)
			(end -0.508 0.9398)
			(stroke
				(width 0.1524)
				(type default)
			)
			(layer "F.SilkS")
		)
		(fp_rect
			(start -0.508 0.9398)
			(end 0.508 -0.9398)
			(stroke
				(width 0)
				(type default)
			)
			(fill no)
			(layer "F.CrtYd")
		)
		(fp_rect
			(start -0.508 0.9398)
			(end 0.508 -0.9398)
			(stroke
				(width 0)
				(type default)
			)
			(fill no)
			(layer "F.Fab")
		)
		(pad "1" smd custom
			(at 0 -0.4445 90)
			(size 0.1397 0.1397)
			(layers "F.Cu" "F.Mask" "F.Paste")
			(net "ATTN_LED_DR4_AND")
			(options
				(clearance outline)
				(anchor circle)
			)
			(primitives
				(gr_poly
					(pts
						(arc
							(start -0.1778 -0.2794)
							(mid -0.249642 -0.249642)
							(end -0.2794 -0.1778)
						)
						(arc
							(start -0.2794 0.1778)
							(mid -0.249642 0.249642)
							(end -0.1778 0.2794)
						)
						(arc
							(start 0.1778 0.2794)
							(mid 0.249642 0.249642)
							(end 0.2794 0.1778)
						)
						(arc
							(start 0.2794 -0.1778)
							(mid 0.249642 -0.249642)
							(end 0.1778 -0.2794)
						)
					)
					(width 0)
					(fill yes)
				)
			)
		)
		(pad "2" smd custom
			(at 0 0.4445 90)
			(size 0.1397 0.1397)
			(layers "F.Cu" "F.Mask" "F.Paste")
			(net "ATTN_LED_DR4_AND_R")
			(options
				(clearance outline)
				(anchor circle)
			)
			(primitives
				(gr_poly
					(pts
						(arc
							(start -0.1778 -0.2794)
							(mid -0.249642 -0.249642)
							(end -0.2794 -0.1778)
						)
						(arc
							(start -0.2794 0.1778)
							(mid -0.249642 0.249642)
							(end -0.1778 0.2794)
						)
						(arc
							(start 0.1778 0.2794)
							(mid 0.249642 0.249642)
							(end 0.2794 0.1778)
						)
						(arc
							(start 0.2794 -0.1778)
							(mid 0.249642 -0.249642)
							(end 0.1778 -0.2794)
						)
					)
					(width 0)
					(fill yes)
				)
			)
		)
	)
	(footprint ""
		(layer "F.Cu")
		(at 217.043 -290.5506 180)
		(property "Reference" "SR1096"
			(at 0 0 180)
			(layer "F.SilkS")
			(hide yes)
			(effects
				(font
					(size 1.27 1.27)
				)
			)
		)
		(property "Value" "4K7R2F-GP"
			(at 0.064008 -3.993896 180)
			(unlocked yes)
			(layer "F.Fab")
			(hide yes)
			(effects
				(font
					(size 1.016 1.016)
					(thickness 0.1524)
				)
			)
		)
		(property "Device Type" "R402H16"
			(at 0.064008 -5.517896 180)
			(unlocked yes)
			(layer "F.Fab")
			(hide yes)
			(effects
				(font
					(size 1.016 1.016)
					(thickness 0.1524)
				)
			)
		)
		(duplicate_pad_numbers_are_jumpers no)
		(fp_line
			(start 0.508 -0.9398)
			(end -0.508 -0.9398)
			(stroke
				(width 0.1524)
				(type default)
			)
			(layer "F.SilkS")
		)
		(fp_line
			(start -0.508 -0.9398)
			(end -0.508 0.9398)
			(stroke
				(width 0.1524)
				(type default)
			)
			(layer "F.SilkS")
		)
		(fp_rect
			(start -0.508 0.9398)
			(end 0.508 -0.9398)
			(stroke
				(width 0)
				(type default)
			)
			(fill no)
			(layer "F.CrtYd")
		)
		(fp_rect
			(start -0.508 0.9398)
			(end 0.508 -0.9398)
			(stroke
				(width 0)
				(type default)
			)
			(fill no)
			(layer "F.Fab")
		)
		(pad "1" smd custom
			(at 0 -0.4445 180)
			(size 0.1397 0.1397)
			(layers "F.Cu" "F.Mask" "F.Paste")
			(net "DUALPORTEN#2")
			(options
				(clearance outline)
				(anchor circle)
			)
			(primitives
				(gr_poly
					(pts
						(arc
							(start -0.1778 -0.2794)
							(mid -0.249642 -0.249642)
							(end -0.2794 -0.1778)
						)
						(arc
							(start -0.2794 0.1778)
							(mid -0.249642 0.249642)
							(end -0.1778 0.2794)
						)
						(arc
							(start 0.1778 0.2794)
							(mid 0.249642 0.249642)
							(end 0.2794 0.1778)
						)
						(arc
							(start 0.2794 -0.1778)
							(mid 0.249642 -0.249642)
							(end 0.1778 -0.2794)
						)
					)
					(width 0)
					(fill yes)
				)
			)
		)
		(pad "2" smd custom
			(at 0 0.4445 180)
			(size 0.1397 0.1397)
			(layers "F.Cu" "F.Mask" "F.Paste")
			(net "GND")
			(options
				(clearance outline)
				(anchor circle)
			)
			(primitives
				(gr_poly
					(pts
						(arc
							(start -0.1778 -0.2794)
							(mid -0.249642 -0.249642)
							(end -0.2794 -0.1778)
						)
						(arc
							(start -0.2794 0.1778)
							(mid -0.249642 0.249642)
							(end -0.1778 0.2794)
						)
						(arc
							(start 0.1778 0.2794)
							(mid 0.249642 0.249642)
							(end 0.2794 0.1778)
						)
						(arc
							(start 0.2794 -0.1778)
							(mid 0.249642 -0.249642)
							(end 0.1778 -0.2794)
						)
					)
					(width 0)
					(fill yes)
				)
			)
		)
	)
	(footprint ""
		(layer "F.Cu")
		(at 222.544894 -40.553894)
		(property "Reference" "Q50"
			(at 0 0 0)
			(layer "F.SilkS")
			(hide yes)
			(effects
				(font
					(size 1.27 1.27)
				)
			)
		)
		(property "Value" "2N7002A-7-GP"
			(at 0.127 -8.9662 0)
			(unlocked yes)
			(layer "F.Fab")
			(hide yes)
			(effects
				(font
					(size 1.016 1.016)
					(thickness 0.1524)
				)
			)
		)
		(property "Device Type" "SOT23DGS2D4H48"
			(at 0.127 -10.4902 0)
			(unlocked yes)
			(layer "F.Fab")
			(hide yes)
			(effects
				(font
					(size 1.016 1.016)
					(thickness 0.1524)
				)
			)
		)
		(duplicate_pad_numbers_are_jumpers no)
		(fp_line
			(start -1.651 -1.778)
			(end -1.651 1.778)
			(stroke
				(width 0.1524)
				(type default)
			)
			(layer "F.SilkS")
		)
		(fp_line
			(start -1.651 1.778)
			(end 1.651 1.778)
			(stroke
				(width 0.1524)
				(type default)
			)
			(layer "F.SilkS")
		)
		(fp_line
			(start 1.651 -1.778)
			(end -1.651 -1.778)
			(stroke
				(width 0.1524)
				(type default)
			)
			(layer "F.SilkS")
		)
		(fp_line
			(start 1.651 1.778)
			(end 1.651 -1.778)
			(stroke
				(width 0.1524)
				(type default)
			)
			(layer "F.SilkS")
		)
		(fp_poly
			(pts
				(xy -1.778 1.8796) (xy -1.778 -1.8796) (xy 1.778 -1.8796) (xy 1.778 1.8796)
			)
			(stroke
				(width 0)
				(type default)
			)
			(fill no)
			(layer "F.CrtYd")
		)
		(fp_poly
			(pts
				(xy -1.778 1.8796) (xy -1.778 -1.8796) (xy 1.778 -1.8796) (xy 1.778 1.8796)
			)
			(stroke
				(width 0)
				(type default)
			)
			(fill no)
			(layer "F.Fab")
		)
		(pad "D" smd custom
			(at 0 -0.9525)
			(size 0.1905 0.1905)
			(layers "F.Cu" "F.Mask" "F.Paste")
			(net "ATTN_LED_DR4_MOS_N")
			(options
				(clearance outline)
				(anchor circle)
			)
			(primitives
				(gr_poly
					(pts
						(arc
							(start -0.1778 0.5715)
							(mid -0.321484 0.511984)
							(end -0.381 0.3683)
						)
						(arc
							(start -0.381 -0.3683)
							(mid -0.321484 -0.511984)
							(end -0.1778 -0.5715)
						)
						(arc
							(start 0.1778 -0.5715)
							(mid 0.321484 -0.511984)
							(end 0.381 -0.3683)
						)
						(arc
							(start 0.381 0.3683)
							(mid 0.321484 0.511984)
							(end 0.1778 0.5715)
						)
					)
					(width 0)
					(fill yes)
				)
			)
		)
		(pad "G" smd custom
			(at -0.98425 0.9525)
			(size 0.1905 0.1905)
			(layers "F.Cu" "F.Mask" "F.Paste")
			(net "SSD4_CLK0_OE_MOS_N")
			(options
				(clearance outline)
				(anchor circle)
			)
			(primitives
				(gr_poly
					(pts
						(arc
							(start -0.1778 0.5715)
							(mid -0.321484 0.511984)
							(end -0.381 0.3683)
						)
						(arc
							(start -0.381 -0.3683)
							(mid -0.321484 -0.511984)
							(end -0.1778 -0.5715)
						)
						(arc
							(start 0.1778 -0.5715)
							(mid 0.321484 -0.511984)
							(end 0.381 -0.3683)
						)
						(arc
							(start 0.381 0.3683)
							(mid 0.321484 0.511984)
							(end 0.1778 0.5715)
						)
					)
					(width 0)
					(fill yes)
				)
			)
		)
		(pad "S" smd custom
			(at 0.98425 0.9525)
			(size 0.1905 0.1905)
			(layers "F.Cu" "F.Mask" "F.Paste")
			(net "ATTN_LED_DR4_R")
			(options
				(clearance outline)
				(anchor circle)
			)
			(primitives
				(gr_poly
					(pts
						(arc
							(start -0.1778 0.5715)
							(mid -0.321484 0.511984)
							(end -0.381 0.3683)
						)
						(arc
							(start -0.381 -0.3683)
							(mid -0.321484 -0.511984)
							(end -0.1778 -0.5715)
						)
						(arc
							(start 0.1778 -0.5715)
							(mid 0.321484 -0.511984)
							(end 0.381 -0.3683)
						)
						(arc
							(start 0.381 0.3683)
							(mid 0.321484 0.511984)
							(end 0.1778 0.5715)
						)
					)
					(width 0)
					(fill yes)
				)
			)
		)
	)
)
